(kicad_pcb
	(version 20260206)
	(generator "pcbnew")
	(generator_version "10.0")
	(general
		(thickness 1.6)
		(legacy_teardrops no)
	)
	(paper "A4")
	(title_block
		(title "Bryce Canyon_F.DPB_16315-1-OCP.brd")
		(comment 1 "Bryce Canyon / footprints 932-936 of 2223")
	)
	(layers
		(0 "F.Cu" signal "TOP")
		(4 "In1.Cu" signal "L2GND")
		(6 "In2.Cu" signal "L3")
		(8 "In3.Cu" signal "L4GND")
		(10 "In4.Cu" signal "L5")
		(12 "In5.Cu" signal "L6VCC")
		(14 "In6.Cu" signal "L7VCC")
		(16 "In7.Cu" signal "L8")
		(18 "In8.Cu" signal "L9GND")
		(20 "In9.Cu" signal "L10")
		(22 "In10.Cu" signal "L11GND")
		(2 "B.Cu" signal "BOTTOM")
		(9 "F.Adhes" user "F.Adhesive")
		(11 "B.Adhes" user "B.Adhesive")
		(13 "F.Paste" user "Package Geometry/Pastemask Top")
		(15 "B.Paste" user "Package Geometry/Pastemask Bottom")
		(5 "F.SilkS" user "Ref Des/Silkscreen Top")
		(7 "B.SilkS" user "Ref Des/Silkscreen Bottom")
		(1 "F.Mask" user "Board Geometry/Soldermask Top")
		(3 "B.Mask" user "Board Geometry/Soldermask Bottom")
		(17 "Dwgs.User" user "User.Drawings")
		(19 "Cmts.User" user "User.Comments")
		(21 "Eco1.User" user "User.Eco1")
		(23 "Eco2.User" user "User.Eco2")
		(25 "Edge.Cuts" user "Board Geometry/Outline")
		(27 "Margin" user)
		(31 "F.CrtYd" user "Package Geometry/Place Bound Top")
		(29 "B.CrtYd" user "Package Geometry/Place Bound Bottom")
		(35 "F.Fab" user "Ref Des/Assembly Top")
		(33 "B.Fab" user "Ref Des/Assembly Bottom")
	)
	(footprint ""
		(layer "F.Cu")
		(at 468.354918 -49.70145)
		(property "Reference" "R949"
			(at 0 0 0)
			(layer "F.SilkS")
			(hide yes)
			(effects
				(font
					(size 1.27 1.27)
				)
			)
		)
		(property "Value" "4K7R2J-2-GP"
			(at 0.064008 -3.993896 0)
			(unlocked yes)
			(layer "F.Fab")
			(hide yes)
			(effects
				(font
					(size 1.016 1.016)
					(thickness 0.1524)
				)
			)
		)
		(property "Device Type" "R402H16"
			(at 0.064008 -5.517896 0)
			(unlocked yes)
			(layer "F.Fab")
			(hide yes)
			(effects
				(font
					(size 1.016 1.016)
					(thickness 0.1524)
				)
			)
		)
		(duplicate_pad_numbers_are_jumpers no)
		(fp_line
			(start -0.508 -0.9398)
			(end -0.508 0.9398)
			(stroke
				(width 0.1524)
				(type default)
			)
			(layer "F.SilkS")
		)
		(fp_line
			(start 0.508 -0.9398)
			(end -0.508 -0.9398)
			(stroke
				(width 0.1524)
				(type default)
			)
			(layer "F.SilkS")
		)
		(fp_rect
			(start -0.508 0.9398)
			(end 0.508 -0.9398)
			(stroke
				(width 0)
				(type default)
			)
			(fill no)
			(layer "F.CrtYd")
		)
		(fp_rect
			(start -0.508 0.9398)
			(end 0.508 -0.9398)
			(stroke
				(width 0)
				(type default)
			)
			(fill no)
			(layer "F.Fab")
		)
		(pad "1" smd custom
			(at 0 -0.4445)
			(size 0.1397 0.1397)
			(layers "F.Cu" "F.Mask" "F.Paste")
			(net "P12V_A")
			(options
				(clearance outline)
				(anchor circle)
			)
			(primitives
				(gr_poly
					(pts
						(arc
							(start -0.1778 -0.2794)
							(mid -0.249642 -0.249642)
							(end -0.2794 -0.1778)
						)
						(arc
							(start -0.2794 0.1778)
							(mid -0.249642 0.249642)
							(end -0.1778 0.2794)
						)
						(arc
							(start 0.1778 0.2794)
							(mid 0.249642 0.249642)
							(end 0.2794 0.1778)
						)
						(arc
							(start 0.2794 -0.1778)
							(mid 0.249642 -0.249642)
							(end 0.1778 -0.2794)
						)
					)
					(width 0)
					(fill yes)
				)
			)
		)
		(pad "2" smd custom
			(at 0 0.4445)
			(size 0.1397 0.1397)
			(layers "F.Cu" "F.Mask" "F.Paste")
			(net "SW_HDD_R35")
			(options
				(clearance outline)
				(anchor circle)
			)
			(primitives
				(gr_poly
					(pts
						(arc
							(start -0.1778 -0.2794)
							(mid -0.249642 -0.249642)
							(end -0.2794 -0.1778)
						)
						(arc
							(start -0.2794 0.1778)
							(mid -0.249642 0.249642)
							(end -0.1778 0.2794)
						)
						(arc
							(start 0.1778 0.2794)
							(mid 0.249642 0.249642)
							(end 0.2794 0.1778)
						)
						(arc
							(start 0.2794 -0.1778)
							(mid 0.249642 -0.249642)
							(end 0.1778 -0.2794)
						)
					)
					(width 0)
					(fill yes)
				)
			)
		)
	)
	(footprint ""
		(layer "F.Cu")
		(at 245.745 -236.982)
		(property "Reference" "U8"
			(at 0 0 0)
			(layer "F.SilkS")
			(hide yes)
			(effects
				(font
					(size 1.27 1.27)
				)
			)
		)
		(property "Value" "TCA9555PWR-GP"
			(at 0 -6.9342 0)
			(unlocked yes)
			(layer "F.Fab")
			(hide yes)
			(effects
				(font
					(size 1.016 1.016)
					(thickness 0.1524)
				)
			)
		)
		(property "Device Type" "TSOIC24H48"
			(at 0 -8.5852 0)
			(unlocked yes)
			(layer "F.Fab")
			(hide yes)
			(effects
				(font
					(size 1.016 1.016)
					(thickness 0.1524)
				)
			)
		)
		(duplicate_pad_numbers_are_jumpers no)
		(fp_line
			(start -4.2291 -1.397)
			(end 3.81 -1.397)
			(stroke
				(width 0.1524)
				(type default)
			)
			(layer "F.SilkS")
		)
		(fp_line
			(start -4.2291 -0.8001)
			(end -3.429 0)
			(stroke
				(width 0.1524)
				(type default)
			)
			(layer "F.SilkS")
		)
		(fp_line
			(start -4.2291 3.937)
			(end -4.2291 -1.397)
			(stroke
				(width 0.1524)
				(type default)
			)
			(layer "F.SilkS")
		)
		(fp_line
			(start -4.22656 3.81)
			(end -4.2291 1.397)
			(stroke
				(width 0.508)
				(type default)
			)
			(layer "F.SilkS")
		)
		(fp_line
			(start -3.429 0)
			(end -4.2291 0.8001)
			(stroke
				(width 0.1524)
				(type default)
			)
			(layer "F.SilkS")
		)
		(fp_line
			(start 3.81 -1.397)
			(end 3.81 1.397)
			(stroke
				(width 0.1524)
				(type default)
			)
			(layer "F.SilkS")
		)
		(fp_line
			(start 3.81 1.397)
			(end -4.2291 1.397)
			(stroke
				(width 0.1524)
				(type default)
			)
			(layer "F.SilkS")
		)
		(fp_poly
			(pts
				(xy -3.90652 -1.8542) (xy 3.90652 -1.8542) (xy 3.90652 1.8542) (xy -3.90652 1.8542)
			)
			(stroke
				(width 0)
				(type default)
			)
			(fill yes)
			(layer "F.SilkS")
		)
		(fp_poly
			(pts
				(xy -4.2164 3.81) (xy 4.2164 3.81) (xy 4.22656 -3.81) (xy -4.2164 -3.81)
			)
			(stroke
				(width 0)
				(type default)
			)
			(fill no)
			(layer "F.CrtYd")
		)
		(fp_poly
			(pts
				(xy -4.22656 -3.81) (xy 4.22656 -3.81) (xy 4.22656 3.81) (xy -4.22656 3.81)
			)
			(stroke
				(width 0)
				(type default)
			)
			(fill no)
			(layer "F.Fab")
		)
		(pad "1" smd rect
			(at -3.57632 2.8194)
			(size 0.3556 1.524)
			(layers "F.Cu" "F.Mask" "F.Paste")
			(net "IO_EXP2_INT_N")
		)
		(pad "2" smd rect
			(at -2.92608 2.8194)
			(size 0.3556 1.524)
			(layers "F.Cu" "F.Mask" "F.Paste")
			(net "IO_EXP2_A1")
		)
		(pad "3" smd rect
			(at -2.27584 2.8194)
			(size 0.3556 1.524)
			(layers "F.Cu" "F.Mask" "F.Paste")
			(net "IO_EXP2_A2")
		)
		(pad "4" smd rect
			(at -1.6256 2.8194)
			(size 0.3556 1.524)
			(layers "F.Cu" "F.Mask" "F.Paste")
			(net "DRIVE_A_16_PWR")
		)
		(pad "5" smd rect
			(at -0.97536 2.8194)
			(size 0.3556 1.524)
			(layers "F.Cu" "F.Mask" "F.Paste")
			(net "DRIVE_A_17_PWR")
		)
		(pad "6" smd rect
			(at -0.32512 2.8194)
			(size 0.3556 1.524)
			(layers "F.Cu" "F.Mask" "F.Paste")
			(net "DRIVE_A_18_PWR")
		)
		(pad "7" smd rect
			(at 0.32512 2.8194)
			(size 0.3556 1.524)
			(layers "F.Cu" "F.Mask" "F.Paste")
			(net "DRIVE_A_19_PWR")
		)
		(pad "8" smd rect
			(at 0.97536 2.8194)
			(size 0.3556 1.524)
			(layers "F.Cu" "F.Mask" "F.Paste")
			(net "DRIVE_A_20_PWR")
		)
		(pad "9" smd rect
			(at 1.6256 2.8194)
			(size 0.3556 1.524)
			(layers "F.Cu" "F.Mask" "F.Paste")
			(net "DRIVE_A_21_PWR")
		)
		(pad "10" smd rect
			(at 2.27584 2.8194)
			(size 0.3556 1.524)
			(layers "F.Cu" "F.Mask" "F.Paste")
			(net "DRIVE_A_22_PWR")
		)
		(pad "11" smd rect
			(at 2.92608 2.8194)
			(size 0.3556 1.524)
			(layers "F.Cu" "F.Mask" "F.Paste")
			(net "DRIVE_A_23_PWR")
		)
		(pad "12" smd rect
			(at 3.57632 2.8194)
			(size 0.3556 1.524)
			(layers "F.Cu" "F.Mask" "F.Paste")
			(net "GND")
		)
		(pad "13" smd rect
			(at 3.57632 -2.8194)
			(size 0.3556 1.524)
			(layers "F.Cu" "F.Mask" "F.Paste")
			(net "DRIVE_A_24_PWR")
		)
		(pad "14" smd rect
			(at 2.92608 -2.8194)
			(size 0.3556 1.524)
			(layers "F.Cu" "F.Mask" "F.Paste")
			(net "DRIVE_A_25_PWR")
		)
		(pad "15" smd rect
			(at 2.27584 -2.8194)
			(size 0.3556 1.524)
			(layers "F.Cu" "F.Mask" "F.Paste")
			(net "DRIVE_A_26_PWR")
		)
		(pad "16" smd rect
			(at 1.6256 -2.8194)
			(size 0.3556 1.524)
			(layers "F.Cu" "F.Mask" "F.Paste")
			(net "DRIVE_A_27_PWR")
		)
		(pad "17" smd rect
			(at 0.97536 -2.8194)
			(size 0.3556 1.524)
			(layers "F.Cu" "F.Mask" "F.Paste")
			(net "DRIVE_A_28_PWR")
		)
		(pad "18" smd rect
			(at 0.32512 -2.8194)
			(size 0.3556 1.524)
			(layers "F.Cu" "F.Mask" "F.Paste")
			(net "DRIVE_A_29_PWR")
		)
		(pad "19" smd rect
			(at -0.32512 -2.8194)
			(size 0.3556 1.524)
			(layers "F.Cu" "F.Mask" "F.Paste")
			(net "DRIVE_A_30_PWR")
		)
		(pad "20" smd rect
			(at -0.97536 -2.8194)
			(size 0.3556 1.524)
			(layers "F.Cu" "F.Mask" "F.Paste")
			(net "DRIVE_A_31_PWR")
		)
		(pad "21" smd rect
			(at -1.6256 -2.8194)
			(size 0.3556 1.524)
			(layers "F.Cu" "F.Mask" "F.Paste")
			(net "IO_EXP2_A0")
		)
		(pad "22" smd rect
			(at -2.27584 -2.8194)
			(size 0.3556 1.524)
			(layers "F.Cu" "F.Mask" "F.Paste")
			(net "IO_EXP2_SCL")
		)
		(pad "23" smd rect
			(at -2.92608 -2.8194)
			(size 0.3556 1.524)
			(layers "F.Cu" "F.Mask" "F.Paste")
			(net "IO_EXP2_SDA")
		)
		(pad "24" smd rect
			(at -3.57632 -2.8194)
			(size 0.3556 1.524)
			(layers "F.Cu" "F.Mask" "F.Paste")
			(net "GPIO_VCC_U8")
		)
	)
	(footprint ""
		(layer "F.Cu")
		(at 46.392846 -289.857942)
		(property "Reference" "Q8"
			(at 0 0 0)
			(layer "F.SilkS")
			(hide yes)
			(effects
				(font
					(size 1.27 1.27)
				)
			)
		)
		(property "Value" "AO4407AL-GP"
			(at -3.707384 -1.5367 0)
			(unlocked yes)
			(layer "F.Fab")
			(hide yes)
			(effects
				(font
					(size 1.016 1.016)
					(thickness 0.1524)
				)
			)
		)
		(property "Device Type" "SOIC8H69"
			(at -3.707384 -3.0607 0)
			(unlocked yes)
			(layer "F.Fab")
			(hide yes)
			(effects
				(font
					(size 1.016 1.016)
					(thickness 0.1524)
				)
			)
		)
		(duplicate_pad_numbers_are_jumpers no)
		(fp_line
			(start -2.7432 -1.4224)
			(end -2.7432 1.4224)
			(stroke
				(width 0.1524)
				(type default)
			)
			(layer "F.SilkS")
		)
		(fp_line
			(start -2.7432 1.4224)
			(end -2.6416 1.4224)
			(stroke
				(width 0.1524)
				(type default)
			)
			(layer "F.SilkS")
		)
		(fp_line
			(start -2.7432 1.4224)
			(end 2.1336 1.4224)
			(stroke
				(width 0.1524)
				(type default)
			)
			(layer "F.SilkS")
		)
		(fp_line
			(start -2.7178 -0.508)
			(end -2.1844 -0.0508)
			(stroke
				(width 0.1524)
				(type default)
			)
			(layer "F.SilkS")
		)
		(fp_line
			(start -2.6289 3.4417)
			(end -2.6289 1.4732)
			(stroke
				(width 0.381)
				(type default)
			)
			(layer "F.SilkS")
		)
		(fp_line
			(start -2.1844 -0.0508)
			(end -2.7178 0.508)
			(stroke
				(width 0.1524)
				(type default)
			)
			(layer "F.SilkS")
		)
		(fp_line
			(start 2.1336 -1.4224)
			(end -2.7432 -1.4224)
			(stroke
				(width 0.1524)
				(type default)
			)
			(layer "F.SilkS")
		)
		(fp_line
			(start 2.1336 1.4224)
			(end 2.1336 -1.4224)
			(stroke
				(width 0.1524)
				(type default)
			)
			(layer "F.SilkS")
		)
		(fp_poly
			(pts
				(xy -2.2098 -1.4224) (xy -2.2098 1.4224) (xy 2.2098 1.4224) (xy 2.2098 -1.4224)
			)
			(stroke
				(width 0)
				(type default)
			)
			(fill yes)
			(layer "F.SilkS")
		)
		(fp_rect
			(start -2.450084 2.999994)
			(end 2.450084 -2.999994)
			(stroke
				(width 0)
				(type default)
			)
			(fill no)
			(layer "F.CrtYd")
		)
		(fp_poly
			(pts
				(xy -2.8194 3.6322) (xy -2.8194 -3.6322) (xy 2.8194 -3.6322) (xy 2.8194 1.18364) (xy 2.450084 1.18364)
				(xy 2.450084 -2.999994) (xy -2.450084 -2.999994) (xy -2.450084 2.999994) (xy 2.450084 2.999994)
				(xy 2.450084 1.18618) (xy 2.8194 1.18618) (xy 2.8194 3.6322)
			)
			(stroke
				(width 0)
				(type default)
			)
			(fill no)
			(layer "F.CrtYd")
		)
		(fp_rect
			(start -2.8194 3.6322)
			(end 2.8194 -3.6322)
			(stroke
				(width 0)
				(type default)
			)
			(fill no)
			(layer "F.Fab")
		)
		(pad "1" smd rect
			(at -1.905 2.54)
			(size 0.635 1.651)
			(layers "F.Cu" "F.Mask" "F.Paste")
			(net "P12V_A")
		)
		(pad "2" smd rect
			(at -0.635 2.54)
			(size 0.635 1.651)
			(layers "F.Cu" "F.Mask" "F.Paste")
			(net "P12V_A")
		)
		(pad "3" smd rect
			(at 0.635 2.54)
			(size 0.635 1.651)
			(layers "F.Cu" "F.Mask" "F.Paste")
			(net "P12V_A")
		)
		(pad "4" smd rect
			(at 1.905 2.54)
			(size 0.635 1.651)
			(layers "F.Cu" "F.Mask" "F.Paste")
			(net "SW_HDD_N1")
		)
		(pad "5" smd rect
			(at 1.905 -2.54)
			(size 0.635 1.651)
			(layers "F.Cu" "F.Mask" "F.Paste")
			(net "P12V_HDD1")
		)
		(pad "6" smd rect
			(at 0.635 -2.54)
			(size 0.635 1.651)
			(layers "F.Cu" "F.Mask" "F.Paste")
			(net "P12V_HDD1")
		)
		(pad "7" smd rect
			(at -0.635 -2.54)
			(size 0.635 1.651)
			(layers "F.Cu" "F.Mask" "F.Paste")
			(net "P12V_HDD1")
		)
		(pad "8" smd rect
			(at -1.905 -2.54)
			(size 0.635 1.651)
			(layers "F.Cu" "F.Mask" "F.Paste")
			(net "P12V_HDD1")
		)
	)
	(footprint ""
		(layer "F.Cu")
		(at 303.4284 -74.7776 180)
		(property "Reference" "R987"
			(at 0 0 180)
			(layer "F.SilkS")
			(hide yes)
			(effects
				(font
					(size 1.27 1.27)
				)
			)
		)
		(property "Value" "100KR2F-L1-GP"
			(at 0.064008 -3.993896 180)
			(unlocked yes)
			(layer "F.Fab")
			(hide yes)
			(effects
				(font
					(size 1.016 1.016)
					(thickness 0.1524)
				)
			)
		)
		(property "Device Type" "R402H16"
			(at 0.064008 -5.517896 180)
			(unlocked yes)
			(layer "F.Fab")
			(hide yes)
			(effects
				(font
					(size 1.016 1.016)
					(thickness 0.1524)
				)
			)
		)
		(duplicate_pad_numbers_are_jumpers no)
		(fp_line
			(start 0.508 -0.9398)
			(end -0.508 -0.9398)
			(stroke
				(width 0.1524)
				(type default)
			)
			(layer "F.SilkS")
		)
		(fp_line
			(start -0.508 -0.9398)
			(end -0.508 0.9398)
			(stroke
				(width 0.1524)
				(type default)
			)
			(layer "F.SilkS")
		)
		(fp_rect
			(start -0.508 0.9398)
			(end 0.508 -0.9398)
			(stroke
				(width 0)
				(type default)
			)
			(fill no)
			(layer "F.CrtYd")
		)
		(fp_rect
			(start -0.508 0.9398)
			(end 0.508 -0.9398)
			(stroke
				(width 0)
				(type default)
			)
			(fill no)
			(layer "F.Fab")
		)
		(pad "1" smd custom
			(at 0 -0.4445 180)
			(size 0.1397 0.1397)
			(layers "F.Cu" "F.Mask" "F.Paste")
			(net "P3V3_STBY_B")
			(options
				(clearance outline)
				(anchor circle)
			)
			(primitives
				(gr_poly
					(pts
						(arc
							(start -0.1778 -0.2794)
							(mid -0.249642 -0.249642)
							(end -0.2794 -0.1778)
						)
						(arc
							(start -0.2794 0.1778)
							(mid -0.249642 0.249642)
							(end -0.1778 0.2794)
						)
						(arc
							(start 0.1778 0.2794)
							(mid 0.249642 0.249642)
							(end 0.2794 0.1778)
						)
						(arc
							(start 0.2794 -0.1778)
							(mid 0.249642 -0.249642)
							(end 0.1778 -0.2794)
						)
					)
					(width 0)
					(fill yes)
				)
			)
		)
		(pad "2" smd custom
			(at 0 0.4445 180)
			(size 0.1397 0.1397)
			(layers "F.Cu" "F.Mask" "F.Paste")
			(net "COMP_B_PRI_INS_N")
			(options
				(clearance outline)
				(anchor circle)
			)
			(primitives
				(gr_poly
					(pts
						(arc
							(start -0.1778 -0.2794)
							(mid -0.249642 -0.249642)
							(end -0.2794 -0.1778)
						)
						(arc
							(start -0.2794 0.1778)
							(mid -0.249642 0.249642)
							(end -0.1778 0.2794)
						)
						(arc
							(start 0.1778 0.2794)
							(mid 0.249642 0.249642)
							(end 0.2794 0.1778)
						)
						(arc
							(start 0.2794 -0.1778)
							(mid 0.249642 -0.249642)
							(end 0.1778 -0.2794)
						)
					)
					(width 0)
					(fill yes)
				)
			)
		)
	)
	(footprint ""
		(layer "F.Cu")
		(at 464.8073 -286.759142 -90)
		(property "Reference" "R375"
			(at 0 0 270)
			(layer "F.SilkS")
			(hide yes)
			(effects
				(font
					(size 1.27 1.27)
				)
			)
		)
		(property "Value" "300KR2F-GP"
			(at 0.064008 -3.993896 270)
			(unlocked yes)
			(layer "F.Fab")
			(hide yes)
			(effects
				(font
					(size 1.016 1.016)
					(thickness 0.1524)
				)
			)
		)
		(property "Device Type" "R402H16"
			(at 0.064008 -5.517896 270)
			(unlocked yes)
			(layer "F.Fab")
			(hide yes)
			(effects
				(font
					(size 1.016 1.016)
					(thickness 0.1524)
				)
			)
		)
		(duplicate_pad_numbers_are_jumpers no)
		(fp_line
			(start -0.508 -0.9398)
			(end -0.508 0.9398)
			(stroke
				(width 0.1524)
				(type default)
			)
			(layer "F.SilkS")
		)
		(fp_line
			(start 0.508 -0.9398)
			(end -0.508 -0.9398)
			(stroke
				(width 0.1524)
				(type default)
			)
			(layer "F.SilkS")
		)
		(fp_rect
			(start -0.508 0.9398)
			(end 0.508 -0.9398)
			(stroke
				(width 0)
				(type default)
			)
			(fill no)
			(layer "F.CrtYd")
		)
		(fp_rect
			(start -0.508 0.9398)
			(end 0.508 -0.9398)
			(stroke
				(width 0)
				(type default)
			)
			(fill no)
			(layer "F.Fab")
		)
		(pad "1" smd custom
			(at 0 -0.4445 270)
			(size 0.1397 0.1397)
			(layers "F.Cu" "F.Mask" "F.Paste")
			(net "SW_HDD_N10")
			(options
				(clearance outline)
				(anchor circle)
			)
			(primitives
				(gr_poly
					(pts
						(arc
							(start -0.1778 -0.2794)
							(mid -0.249642 -0.249642)
							(end -0.2794 -0.1778)
						)
						(arc
							(start -0.2794 0.1778)
							(mid -0.249642 0.249642)
							(end -0.1778 0.2794)
						)
						(arc
							(start 0.1778 0.2794)
							(mid 0.249642 0.249642)
							(end 0.2794 0.1778)
						)
						(arc
							(start 0.2794 -0.1778)
							(mid 0.249642 -0.249642)
							(end 0.1778 -0.2794)
						)
					)
					(width 0)
					(fill yes)
				)
			)
		)
		(pad "2" smd custom
			(at 0 0.4445 270)
			(size 0.1397 0.1397)
			(layers "F.Cu" "F.Mask" "F.Paste")
			(net "P12V_A")
			(options
				(clearance outline)
				(anchor circle)
			)
			(primitives
				(gr_poly
					(pts
						(arc
							(start -0.1778 -0.2794)
							(mid -0.249642 -0.249642)
							(end -0.2794 -0.1778)
						)
						(arc
							(start -0.2794 0.1778)
							(mid -0.249642 0.249642)
							(end -0.1778 0.2794)
						)
						(arc
							(start 0.1778 0.2794)
							(mid 0.249642 0.249642)
							(end 0.2794 0.1778)
						)
						(arc
							(start 0.2794 -0.1778)
							(mid 0.249642 -0.249642)
							(end 0.1778 -0.2794)
						)
					)
					(width 0)
					(fill yes)
				)
			)
		)
	)
)
